# T6G (Grand Teton) — schematic netlist excerpt (pin names and nets, part order shuffled) for the footprints in the layout excerpt that follows; sources: Cadence DE-HDL packaged netlist, KiCad conversion of 04192023_DAF0TMB3IC0_F0TG_MB_C_brd_V02_OCP.brd

J67  SCONN288_DDR506112002KQ  IO  pkg DDR288S_1-1VXC  page 97
  VIN_BULK0  = P12V_MEM_CPU0
  RFU0  = NC
  VIN_MGMT  = P3V3_AUX
  HSCL  = I3C_SPD_DDRL_CPU0_SCL
  HSDA  = I3C_SPD_DDRL_CPU0_SDA
  VSS0  = GND
  DQ0_A  = M_L_CPU0_SA_DQ<0>
  VSS1  = GND
  DQ1_A  = M_L_CPU0_SA_DQ<1>
  VSS2  = GND
  DQS0_A_T  = M_L_CPU0_SA_DQS_DP<0>
  DQS0_A_C  = M_L_CPU0_SA_DQS_DN<0>
  VSS3  = GND
  DQ4_A  = M_L_CPU0_SA_DQ<4>
  VSS4  = GND
  DQ5_A  = M_L_CPU0_SA_DQ<5>
  VSS5  = GND
  DQ8_A  = M_L_CPU0_SA_DQ<8>
  VSS6  = GND
  DQ9_A  = M_L_CPU0_SA_DQ<9>
  VSS7  = GND
  DQS1_A_T  = M_L_CPU0_SA_DQS_DP<1>
  DQS1_A_C  = M_L_CPU0_SA_DQS_DN<1>
  VSS8  = GND
  DQ12_A  = M_L_CPU0_SA_DQ<12>
  VSS9  = GND
  DQ13_A  = M_L_CPU0_SA_DQ<13>
  VSS10  = GND
  DQ16_A  = M_L_CPU0_SA_DQ<16>
  VSS11  = GND
  DQ17_A  = M_L_CPU0_SA_DQ<17>
  VSS12  = GND
  DQS2_A_T  = M_L_CPU0_SA_DQS_DP<2>
  DQS2_A_C  = M_L_CPU0_SA_DQS_DN<2>
  VSS13  = GND
  DQ20_A  = M_L_CPU0_SA_DQ<20>
  VSS14  = GND
  DQ21_A  = M_L_CPU0_SA_DQ<21>
  VSS15  = GND
  DQ24_A  = M_L_CPU0_SA_DQ<24>
  VSS16  = GND
  DQ25_A  = M_L_CPU0_SA_DQ<25>
  VSS17  = GND
  DQS3_A_T  = M_L_CPU0_SA_DQS_DP<3>
  DQS3_A_C  = M_L_CPU0_SA_DQS_DN<3>
  VSS18  = GND
  DQ28_A  = M_L_CPU0_SA_DQ<28>
  VSS19  = GND
  DQ29_A  = M_L_CPU0_SA_DQ<29>
  VSS20  = GND
  CB0_A  = M_L_CPU0_SA_CB<0>
  VSS21  = GND
  CB1_A  = M_L_CPU0_SA_CB<1>
  VSS22  = GND
  DQS4_A_T  = M_L_CPU0_SA_DQS_DP<4>
  DQS4_A_C  = M_L_CPU0_SA_DQS_DN<4>
  VSS23  = GND
  CB4_A  = M_L_CPU0_SA_CB<4>
  VSS24  = GND
  CB5_A  = M_L_CPU0_SA_CB<5>
  VSS25  = GND
  ALERT_N  = M_L_CPU0_ALERT_N
  VSS26  = GND
  CS0_A_N  = M_L_CPU0_SA_CS_N<0>
  VSS27  = GND
  CA0_A  = M_L_CPU0_SA_CA<0>
  VSS28  = GND
  CA2_A  = M_L_CPU0_SA_CA<2>
  VSS29  = GND
  CA4_A  = M_L_CPU0_SA_CA<4>
  VSS30  = GND
  CA6_A  = M_L_CPU0_SA_CA<6>
  VSS31  = GND
  PAR_A  = M_L_CPU0_SA_PAR
  VSS32  = GND
  CA0_B  = M_L_CPU0_SB_CA<0>
  VSS33  = GND
  CA2_B  = M_L_CPU0_SB_CA<2>
  VSS34  = GND
  CA4_B  = M_L_CPU0_SB_CA<4>
  VSS35  = GND
  CA6_B  = M_L_CPU0_SB_CA<6>
  VSS36  = GND
  CS0_B_N  = M_L_CPU0_SB_CS_N<0>
  VSS37  = GND
  \lbd||rsp_a_n\  = M_L_CPU0_SA_RSP<0>
  \lbs||rsp_b_n\  = M_L_CPU0_SB_RSP<0>
  VSS38  = GND
  CB4_B  = M_L_CPU0_SB_CB<4>
  VSS39  = GND
  CB5_B  = M_L_CPU0_SB_CB<5>
  VSS40  = GND
  \dqs9_b_t||tdqs9_b_t||dbi4_b_n\  = M_L_CPU0_SB_DQS_DP<9>
  \dqs9_b_c||tdqs9_b_c\  = M_L_CPU0_SB_DQS_DN<9>
  VSS41  = GND
  CB0_B  = M_L_CPU0_SB_CB<0>
  VSS42  = GND
  CB1_B  = M_L_CPU0_SB_CB<1>
  VSS43  = GND
  DQ0_B  = M_L_CPU0_SB_DQ<0>
  VSS44  = GND
  DQ1_B  = M_L_CPU0_SB_DQ<1>
  VSS45  = GND
  DQS0_B_T  = M_L_CPU0_SB_DQS_DP<0>
  DQS0_B_C  = M_L_CPU0_SB_DQS_DN<0>
  VSS46  = GND
  DQ4_B  = M_L_CPU0_SB_DQ<4>
  VSS47  = GND
  DQ5_B  = M_L_CPU0_SB_DQ<5>
  VSS48  = GND
  DQ8_B  = M_L_CPU0_SB_DQ<8>
  VSS49  = GND
  DQ9_B  = M_L_CPU0_SB_DQ<9>
  VSS50  = GND
  DQS1_B_T  = M_L_CPU0_SB_DQS_DP<1>
  DQS1_B_C  = M_L_CPU0_SB_DQS_DN<1>
  VSS51  = GND
  DQ12_B  = M_L_CPU0_SB_DQ<12>
  VSS52  = GND
  DQ13_B  = M_L_CPU0_SB_DQ<13>
  VSS53  = GND
  DQ16_B  = M_L_CPU0_SB_DQ<16>
  VSS54  = GND
  DQ17_B  = M_L_CPU0_SB_DQ<17>
  VSS55  = GND
  DQS2_B_T  = M_L_CPU0_SB_DQS_DP<2>
  DQS2_B_C  = M_L_CPU0_SB_DQS_DN<2>
  VSS56  = GND
  DQ20_B  = M_L_CPU0_SB_DQ<20>
  VSS57  = GND
  DQ21_B  = M_L_CPU0_SB_DQ<21>
  VSS58  = GND
  DQ24_B  = M_L_CPU0_SB_DQ<24>
  VSS59  = GND
  DQ25_B  = M_L_CPU0_SB_DQ<25>
  VSS60  = GND
  DQS3_B_T  = M_L_CPU0_SB_DQS_DP<3>
  DQS3_B_C  = M_L_CPU0_SB_DQS_DN<3>
  VSS61  = GND
  DQ28_B  = M_L_CPU0_SB_DQ<28>
  VSS62  = GND
  DQ29_B  = M_L_CPU0_SB_DQ<29>
  VSS63  = GND
  RFU1  = NC
  VIN_BULK1  = P12V_MEM_CPU0
  VIN_BULK2  = P12V_MEM_CPU0
  \pwr_good||fail_n\  = PWRGD_CHL_CPU0_DIMM
  HAS  = PD_CHL_CPU0_DIMM_SAA
  RFU2  = NC
  RFU3  = NC
  VSS64  = GND
  DQ2_A  = M_L_CPU0_SA_DQ<2>
  VSS65  = GND
  DQ3_A  = M_L_CPU0_SA_DQ<3>
  VSS66  = GND
  \dqs5_a_c||tdqs5_a_c||dqs5_a_t||tdqs5_a_t\  = M_L_CPU0_SA_DQS_DN<5>
  \dqs5_a_t||tdqs5_a_t\  = M_L_CPU0_SA_DQS_DP<5>
  VSS67  = GND
  DQ6_A  = M_L_CPU0_SA_DQ<6>
  VSS68  = GND
  DQ7_A  = M_L_CPU0_SA_DQ<7>
  VSS69  = GND
  DQ10_A  = M_L_CPU0_SA_DQ<10>
  VSS70  = GND
  DQ11_A  = M_L_CPU0_SA_DQ<11>
  VSS71  = GND
  \dqs6_a_c||tdqs6_a_c||dqs6_a_t||tdqs6_a_t\  = M_L_CPU0_SA_DQS_DN<6>
  \dqs6_a_t||tdqs6_a_t\  = M_L_CPU0_SA_DQS_DP<6>
  VSS72  = GND
  DQ14_A  = M_L_CPU0_SA_DQ<14>
  VSS73  = GND
  DQ15_A  = M_L_CPU0_SA_DQ<15>
  VSS74  = GND
  DQ18_A  = M_L_CPU0_SA_DQ<18>
  VSS75  = GND
  DQ19_A  = M_L_CPU0_SA_DQ<19>
  VSS76  = GND
  \dqs7_a_c||tdqs7_a_c\  = M_L_CPU0_SA_DQS_DN<7>
  \dqs7_a_t||tdqs7_a_t\  = M_L_CPU0_SA_DQS_DP<7>
  VSS77  = GND
  DQ22_A  = M_L_CPU0_SA_DQ<22>
  VSS78  = GND
  DQ23_A  = M_L_CPU0_SA_DQ<23>
  VSS79  = GND
  DQ26_A  = M_L_CPU0_SA_DQ<26>
  VSS80  = GND
  DQ27_A  = M_L_CPU0_SA_DQ<27>
  VSS81  = GND
  \dqs8_a_c||tdqs8_a_c\  = M_L_CPU0_SA_DQS_DN<8>
  \dqs8_a_t||tdqs8_a_t\  = M_L_CPU0_SA_DQS_DP<8>
  VSS82  = GND
  DQ30_A  = M_L_CPU0_SA_DQ<30>
  VSS83  = GND
  DQ31_A  = M_L_CPU0_SA_DQ<31>
  VSS84  = GND
  CB2_A  = M_L_CPU0_SA_CB<2>
  VSS85  = GND
  CB3_A  = M_L_CPU0_SA_CB<3>
  VSS86  = GND
  \dqs9_a_c||tdqs9_a_c\  = M_L_CPU0_SA_DQS_DN<9>
  \dqs9_a_t||tdqs9_a_t\  = M_L_CPU0_SA_DQS_DP<9>
  VSS87  = GND
  CB6_A  = M_L_CPU0_SA_CB<6>
  VSS88  = GND
  CB7_A  = M_L_CPU0_SA_CB<7>
  VSS89  = GND
  RESET_N  = M_L_CPU0_RESET_N
  VSS90  = GND
  CS1_A_N  = M_L_CPU0_SA_CS_N<1>
  VSS91  = GND
  CA1_A  = M_L_CPU0_SA_CA<1>
  VSS92  = GND
  CA3_A  = M_L_CPU0_SA_CA<3>
  VSS93  = GND
  CA5_A  = M_L_CPU0_SA_CA<5>
  VSS94  = GND
  CK_T  = M_L_CPU0_CLK_DP<0>
  CK_C  = M_L_CPU0_CLK_DN<0>
  VSS95  = GND
  RFU4  = NC
  CA1_B  = M_L_CPU0_SB_CA<1>
  VSS96  = GND
  CA3_B  = M_L_CPU0_SB_CA<3>
  VSS97  = GND
  CA5_B  = M_L_CPU0_SB_CA<5>
  VSS98  = GND
  PAR_B  = M_L_CPU0_SB_PAR
  VSS99  = GND
  CS1_B_N  = M_L_CPU0_SB_CS_N<1>
  VSS100  = GND
  RFU5  = NC
  RFU6  = NC
  VSS101  = GND
  CB6_B  = M_L_CPU0_SB_CB<6>
  VSS102  = GND
  CB7_B  = M_L_CPU0_SB_CB<7>
  VSS103  = GND
  DQS4_B_C  = M_L_CPU0_SB_DQS_DN<4>
  DQS4_B_T  = M_L_CPU0_SB_DQS_DP<4>
  VSS104  = GND
  CB2_B  = M_L_CPU0_SB_CB<2>
  VSS105  = GND
  CB3_B  = M_L_CPU0_SB_CB<3>
  VSS106  = GND
  DQ2_B  = M_L_CPU0_SB_DQ<2>
  VSS107  = GND
  DQ3_B  = M_L_CPU0_SB_DQ<3>
  VSS108  = GND
  \dqs5_b_c||tdqs5_b_c\  = M_L_CPU0_SB_DQS_DN<5>
  \dqs5_b_t||tdqs5_b_t\  = M_L_CPU0_SB_DQS_DP<5>
  VSS109  = GND
  DQ6_B  = M_L_CPU0_SB_DQ<6>
  VSS110  = GND
  DQ7_B  = M_L_CPU0_SB_DQ<7>
  VSS111  = GND
  DQ10_B  = M_L_CPU0_SB_DQ<10>
  VSS112  = GND
  DQ11_B  = M_L_CPU0_SB_DQ<11>
  VSS113  = GND
  \dqs6_b_c||tdqs6_b_c\  = M_L_CPU0_SB_DQS_DN<6>
  \dqs6_b_t||tdqs6_b_t\  = M_L_CPU0_SB_DQS_DP<6>
  VSS114  = GND
  DQ14_B  = M_L_CPU0_SB_DQ<14>
  VSS115  = GND
  DQ15_B  = M_L_CPU0_SB_DQ<15>
  VSS116  = GND
  DQ18_B  = M_L_CPU0_SB_DQ<18>
  VSS117  = GND
  DQ19_B  = M_L_CPU0_SB_DQ<19>
  VSS118  = GND
  \dqs7_b_c||tdqs7_b_c\  = M_L_CPU0_SB_DQS_DN<7>
  \dqs7_b_t||tdqs7_b_t\  = M_L_CPU0_SB_DQS_DP<7>
  VSS119  = GND
  DQ22_B  = M_L_CPU0_SB_DQ<22>
  VSS120  = GND
  DQ23_B  = M_L_CPU0_SB_DQ<23>
  VSS121  = GND
  DQ26_B  = M_L_CPU0_SB_DQ<26>
  VSS122  = GND
  DQ27_B  = M_L_CPU0_SB_DQ<27>
  VSS123  = GND
  \dqs8_b_c||tdqs8_b_c\  = M_L_CPU0_SB_DQS_DN<8>
  \dqs8_b_t||tdqs8_b_t\  = M_L_CPU0_SB_DQS_DP<8>
  VSS124  = GND
  DQ30_B  = M_L_CPU0_SB_DQ<30>
  VSS125  = GND
  DQ31_B  = M_L_CPU0_SB_DQ<31>
  VSS126  = GND
  G1  = GND
  G2  = GND
  G3  = GND

(kicad_pcb
	(version 20260206)
	(generator "pcbnew")
	(generator_version "10.0")
	(general
		(thickness 1.6)
		(legacy_teardrops no)
	)
	(paper "A4")
	(title_block
		(title "04192023_DAF0TMB3IC0_F0TG_MB_C_brd_V02_OCP.brd")
		(comment 1 "Grand Teton / footprint 3721 of 8354 (J67), pads 185-230 of 291")
	)
	(layers
		(0 "F.Cu" signal "TOP")
		(4 "In1.Cu" signal "GND")
		(6 "In2.Cu" signal "IN1")
		(8 "In3.Cu" signal "GND1")
		(10 "In4.Cu" signal "IN2")
		(12 "In5.Cu" signal "GND2")
		(14 "In6.Cu" signal "IN3")
		(16 "In7.Cu" signal "GND3")
		(18 "In8.Cu" signal "VCC")
		(20 "In9.Cu" signal "VCC1")
		(22 "In10.Cu" signal "GND4")
		(24 "In11.Cu" signal "IN4")
		(26 "In12.Cu" signal "GND5")
		(28 "In13.Cu" signal "IN5")
		(30 "In14.Cu" signal "GND6")
		(32 "In15.Cu" signal "IN6")
		(34 "In16.Cu" signal "GND7")
		(2 "B.Cu" signal "BOTTOM")
		(9 "F.Adhes" user "F.Adhesive")
		(11 "B.Adhes" user "B.Adhesive")
		(13 "F.Paste" user "Package Geometry/Pastemask Top")
		(15 "B.Paste" user "Package Geometry/Pastemask Bottom")
		(5 "F.SilkS" user "Ref Des/Silkscreen Top")
		(7 "B.SilkS" user "Ref Des/Silkscreen Bottom")
		(1 "F.Mask" user "Board Geometry/Soldermask Top")
		(3 "B.Mask" user "Board Geometry/Soldermask Bottom")
		(17 "Dwgs.User" user "User.Drawings")
		(19 "Cmts.User" user "User.Comments")
		(21 "Eco1.User" user "User.Eco1")
		(23 "Eco2.User" user "User.Eco2")
		(25 "Edge.Cuts" user "Board Geometry/Outline")
		(27 "Margin" user)
		(31 "F.CrtYd" user "Package Geometry/Place Bound Top")
		(29 "B.CrtYd" user "Package Geometry/Place Bound Bottom")
		(35 "F.Fab" user "Ref Des/Assembly Top")
		(33 "B.Fab" user "Ref Des/Assembly Bottom")
	)
	(footprint ""
		(layer "F.Cu")
		(at 452.138034 -255.560068 180)
		(property "Reference" "J67"
			(at 2.380488 -81.709768 0)
			(unlocked yes)
			(layer "F.SilkS")
			(effects
				(font
					(size 0.7874 0.5842)
					(thickness 0.1524)
				)
			)
		)
		(property "Value" ""
			(at 0 0 180)
			(layer "F.Fab")
			(effects
				(font
					(size 1.27 1.27)
				)
			)
		)
		(duplicate_pad_numbers_are_jumpers no)
		(pad "185" smd rect
			(at 2.050034 -29.325062 90)
			(size 0.519938 1.4986)
			(layers "F.Cu" "F.Mask" "F.Paste")
			(net "M_L_CPU0_SA_DQ<26>")
		)
		(pad "186" smd rect
			(at 2.050034 -28.474924 90)
			(size 0.519938 1.4986)
			(layers "F.Cu" "F.Mask" "F.Paste")
			(net "GND")
		)
		(pad "187" smd rect
			(at 2.050034 -27.62504 90)
			(size 0.519938 1.4986)
			(layers "F.Cu" "F.Mask" "F.Paste")
			(net "M_L_CPU0_SA_DQ<27>")
		)
		(pad "188" smd rect
			(at 2.050034 -26.774902 90)
			(size 0.519938 1.4986)
			(layers "F.Cu" "F.Mask" "F.Paste")
			(net "GND")
		)
		(pad "189" smd rect
			(at 2.050034 -25.925018 90)
			(size 0.519938 1.4986)
			(layers "F.Cu" "F.Mask" "F.Paste")
			(net "M_L_CPU0_SA_DQS_DN<8>")
		)
		(pad "190" smd rect
			(at 2.050034 -25.07488 90)
			(size 0.519938 1.4986)
			(layers "F.Cu" "F.Mask" "F.Paste")
			(net "M_L_CPU0_SA_DQS_DP<8>")
		)
		(pad "191" smd rect
			(at 2.050034 -24.224996 90)
			(size 0.519938 1.4986)
			(layers "F.Cu" "F.Mask" "F.Paste")
			(net "GND")
		)
		(pad "192" smd rect
			(at 2.050034 -23.375112 90)
			(size 0.519938 1.4986)
			(layers "F.Cu" "F.Mask" "F.Paste")
			(net "M_L_CPU0_SA_DQ<30>")
		)
		(pad "193" smd rect
			(at 2.050034 -22.524974 90)
			(size 0.519938 1.4986)
			(layers "F.Cu" "F.Mask" "F.Paste")
			(net "GND")
		)
		(pad "194" smd rect
			(at 2.050034 -21.67509 90)
			(size 0.519938 1.4986)
			(layers "F.Cu" "F.Mask" "F.Paste")
			(net "M_L_CPU0_SA_DQ<31>")
		)
		(pad "195" smd rect
			(at 2.050034 -20.824952 90)
			(size 0.519938 1.4986)
			(layers "F.Cu" "F.Mask" "F.Paste")
			(net "GND")
		)
		(pad "196" smd rect
			(at 2.050034 -19.975068 90)
			(size 0.519938 1.4986)
			(layers "F.Cu" "F.Mask" "F.Paste")
			(net "M_L_CPU0_SA_CB<2>")
		)
		(pad "197" smd rect
			(at 2.050034 -19.12493 90)
			(size 0.519938 1.4986)
			(layers "F.Cu" "F.Mask" "F.Paste")
			(net "GND")
		)
		(pad "198" smd rect
			(at 2.050034 -18.275046 90)
			(size 0.519938 1.4986)
			(layers "F.Cu" "F.Mask" "F.Paste")
			(net "M_L_CPU0_SA_CB<3>")
		)
		(pad "199" smd rect
			(at 2.050034 -17.424908 90)
			(size 0.519938 1.4986)
			(layers "F.Cu" "F.Mask" "F.Paste")
			(net "GND")
		)
		(pad "200" smd rect
			(at 2.050034 -16.575024 90)
			(size 0.519938 1.4986)
			(layers "F.Cu" "F.Mask" "F.Paste")
			(net "M_L_CPU0_SA_DQS_DN<9>")
		)
		(pad "201" smd rect
			(at 2.050034 -15.724886 90)
			(size 0.519938 1.4986)
			(layers "F.Cu" "F.Mask" "F.Paste")
			(net "M_L_CPU0_SA_DQS_DP<9>")
		)
		(pad "202" smd rect
			(at 2.050034 -14.875002 90)
			(size 0.519938 1.4986)
			(layers "F.Cu" "F.Mask" "F.Paste")
			(net "GND")
		)
		(pad "203" smd rect
			(at 2.050034 -14.025118 90)
			(size 0.519938 1.4986)
			(layers "F.Cu" "F.Mask" "F.Paste")
			(net "M_L_CPU0_SA_CB<6>")
		)
		(pad "204" smd rect
			(at 2.050034 -13.17498 90)
			(size 0.519938 1.4986)
			(layers "F.Cu" "F.Mask" "F.Paste")
			(net "GND")
		)
		(pad "205" smd rect
			(at 2.050034 -12.325096 90)
			(size 0.519938 1.4986)
			(layers "F.Cu" "F.Mask" "F.Paste")
			(net "M_L_CPU0_SA_CB<7>")
		)
		(pad "206" smd rect
			(at 2.050034 -11.474958 90)
			(size 0.519938 1.4986)
			(layers "F.Cu" "F.Mask" "F.Paste")
			(net "GND")
		)
		(pad "207" smd rect
			(at 2.050034 -10.625074 90)
			(size 0.519938 1.4986)
			(layers "F.Cu" "F.Mask" "F.Paste")
			(net "M_L_CPU0_RESET_N")
		)
		(pad "208" smd rect
			(at 2.050034 -9.774936 90)
			(size 0.519938 1.4986)
			(layers "F.Cu" "F.Mask" "F.Paste")
			(net "GND")
		)
		(pad "209" smd rect
			(at 2.050034 -8.925052 90)
			(size 0.519938 1.4986)
			(layers "F.Cu" "F.Mask" "F.Paste")
			(net "M_L_CPU0_SA_CS_N<1>")
		)
		(pad "210" smd rect
			(at 2.050034 -8.074914 90)
			(size 0.519938 1.4986)
			(layers "F.Cu" "F.Mask" "F.Paste")
			(net "GND")
		)
		(pad "211" smd rect
			(at 2.050034 -7.22503 90)
			(size 0.519938 1.4986)
			(layers "F.Cu" "F.Mask" "F.Paste")
			(net "M_L_CPU0_SA_CA<1>")
		)
		(pad "212" smd rect
			(at 2.050034 -6.374892 90)
			(size 0.519938 1.4986)
			(layers "F.Cu" "F.Mask" "F.Paste")
			(net "GND")
		)
		(pad "213" smd rect
			(at 2.050034 -5.525008 90)
			(size 0.519938 1.4986)
			(layers "F.Cu" "F.Mask" "F.Paste")
			(net "M_L_CPU0_SA_CA<3>")
		)
		(pad "214" smd rect
			(at 2.050034 -4.675124 90)
			(size 0.519938 1.4986)
			(layers "F.Cu" "F.Mask" "F.Paste")
			(net "GND")
		)
		(pad "215" smd rect
			(at 2.050034 -3.824986 90)
			(size 0.519938 1.4986)
			(layers "F.Cu" "F.Mask" "F.Paste")
			(net "M_L_CPU0_SA_CA<5>")
		)
		(pad "216" smd rect
			(at 2.050034 -2.975102 90)
			(size 0.519938 1.4986)
			(layers "F.Cu" "F.Mask" "F.Paste")
			(net "GND")
		)
		(pad "217" smd rect
			(at 2.050034 -2.124964 90)
			(size 0.519938 1.4986)
			(layers "F.Cu" "F.Mask" "F.Paste")
			(net "M_L_CPU0_CLK_DP<0>")
		)
		(pad "218" smd rect
			(at 2.050034 -1.27508 90)
			(size 0.519938 1.4986)
			(layers "F.Cu" "F.Mask" "F.Paste")
			(net "M_L_CPU0_CLK_DN<0>")
		)
		(pad "219" smd rect
			(at 2.050034 -0.424942 90)
			(size 0.519938 1.4986)
			(layers "F.Cu" "F.Mask" "F.Paste")
			(net "GND")
		)
		(pad "220" smd rect
			(at 2.050034 5.525008 90)
			(size 0.519938 1.4986)
			(layers "F.Cu" "F.Mask" "F.Paste")
			(net "Net_2407")
		)
		(pad "221" smd rect
			(at 2.050034 6.374892 90)
			(size 0.519938 1.4986)
			(layers "F.Cu" "F.Mask" "F.Paste")
			(net "M_L_CPU0_SB_CA<1>")
		)
		(pad "222" smd rect
			(at 2.050034 7.22503 90)
			(size 0.519938 1.4986)
			(layers "F.Cu" "F.Mask" "F.Paste")
			(net "GND")
		)
		(pad "223" smd rect
			(at 2.050034 8.074914 90)
			(size 0.519938 1.4986)
			(layers "F.Cu" "F.Mask" "F.Paste")
			(net "M_L_CPU0_SB_CA<3>")
		)
		(pad "224" smd rect
			(at 2.050034 8.925052 90)
			(size 0.519938 1.4986)
			(layers "F.Cu" "F.Mask" "F.Paste")
			(net "GND")
		)
		(pad "225" smd rect
			(at 2.050034 9.774936 90)
			(size 0.519938 1.4986)
			(layers "F.Cu" "F.Mask" "F.Paste")
			(net "M_L_CPU0_SB_CA<5>")
		)
		(pad "226" smd rect
			(at 2.050034 10.625074 90)
			(size 0.519938 1.4986)
			(layers "F.Cu" "F.Mask" "F.Paste")
			(net "GND")
		)
		(pad "227" smd rect
			(at 2.050034 11.474958 90)
			(size 0.519938 1.4986)
			(layers "F.Cu" "F.Mask" "F.Paste")
			(net "M_L_CPU0_SB_PAR")
		)
		(pad "228" smd rect
			(at 2.050034 12.325096 90)
			(size 0.519938 1.4986)
			(layers "F.Cu" "F.Mask" "F.Paste")
			(net "GND")
		)
		(pad "229" smd rect
			(at 2.050034 13.17498 90)
			(size 0.519938 1.4986)
			(layers "F.Cu" "F.Mask" "F.Paste")
			(net "M_L_CPU0_SB_CS_N<1>")
		)
		(pad "230" smd rect
			(at 2.050034 14.025118 90)
			(size 0.519938 1.4986)
			(layers "F.Cu" "F.Mask" "F.Paste")
			(net "GND")
		)
	)
)
